# S9S_MB_2U (Grand Teton) — schematic netlist excerpt (pin names and nets, part order shuffled) for the footprints in the layout excerpt that follows; sources: Cadence DE-HDL packaged netlist, KiCad conversion of 03242023_DA0F0TMBIJ0_F0T_Motherboard_J_brd_V01_OCP.brd

J110  CONN112_10137002101LF  CONN112_10137002-101LF IO  pkg HSD_F112D8_P2W1-2_RDH  page 141
  A1  = GPU_FPGA_EROT_RECOV_BUF_N
  A2  = GND
  A3  = GPU_HMC_PRSNT_N
  A4  = GND
  A5  = GPU_BASE_HMC_READY
  A6  = GND
  A7  = GPU_BASE_STBY_EN_BUF
  A8  = GND
  B1  = GND
  B2  = P5E_CPU1_PE3_RX_DP<14>
  B3  = GND
  B4  = P5E_CPU1_PE3_RX_DP<12>
  B5  = GND
  B6  = P5E_CPU1_PE3_RX_DN<10>
  B7  = GND
  B8  = P5E_CPU1_PE3_RX_DN<8>
  C1  = P5E_CPU1_PE3_RX_DP<15>
  C2  = P5E_CPU1_PE3_RX_DN<14>
  C3  = P5E_CPU1_PE3_RX_DP<13>
  C4  = P5E_CPU1_PE3_RX_DN<12>
  C5  = P5E_CPU1_PE3_RX_DN<11>
  C6  = P5E_CPU1_PE3_RX_DP<10>
  C7  = P5E_CPU1_PE3_RX_DN<9>
  C8  = P5E_CPU1_PE3_RX_DP<8>
  D1  = P5E_CPU1_PE3_RX_DN<15>
  D2  = GND
  D3  = P5E_CPU1_PE3_RX_DN<13>
  D4  = GND
  D5  = P5E_CPU1_PE3_RX_DP<11>
  D6  = GND
  D7  = P5E_CPU1_PE3_RX_DP<9>
  D8  = GND
  E1  = GND
  E2  = P5E_CPU1_PE2_RX_DP<14>
  E3  = GND
  E4  = P5E_CPU1_PE2_RX_DP<12>
  E5  = GND
  E6  = P5E_CPU1_PE2_RX_DP<10>
  E7  = GND
  E8  = P5E_CPU1_PE2_RX_DP<8>
  F1  = P5E_CPU1_PE2_RX_DP<15>
  F2  = P5E_CPU1_PE2_RX_DN<14>
  F3  = P5E_CPU1_PE2_RX_DP<13>
  F4  = P5E_CPU1_PE2_RX_DN<12>
  F5  = P5E_CPU1_PE2_RX_DP<11>
  F6  = P5E_CPU1_PE2_RX_DN<10>
  F7  = P5E_CPU1_PE2_RX_DP<9>
  F8  = P5E_CPU1_PE2_RX_DN<8>
  G1  = P5E_CPU1_PE2_RX_DN<15>
  G2  = GND
  G3  = P5E_CPU1_PE2_RX_DN<13>
  G4  = GND
  G5  = P5E_CPU1_PE2_RX_DN<11>
  G6  = GND
  G7  = P5E_CPU1_PE2_RX_DN<9>
  G8  = GND
  H1  = GND
  H2  = P5E_CPU1_PE3_TX_C_DN<14>
  H3  = GND
  H4  = P5E_CPU1_PE3_TX_C_DN<12>
  H5  = GND
  H6  = P5E_CPU1_PE3_TX_C_DN<10>
  H7  = GND
  H8  = P5E_CPU1_PE3_TX_C_DN<8>
  I1  = P5E_CPU1_PE3_TX_C_DN<15>
  I2  = P5E_CPU1_PE3_TX_C_DP<14>
  I3  = P5E_CPU1_PE3_TX_C_DN<13>
  I4  = P5E_CPU1_PE3_TX_C_DP<12>
  I5  = P5E_CPU1_PE3_TX_C_DN<11>
  I6  = P5E_CPU1_PE3_TX_C_DP<10>
  I7  = P5E_CPU1_PE3_TX_C_DN<9>
  I8  = P5E_CPU1_PE3_TX_C_DP<8>
  J1  = P5E_CPU1_PE3_TX_C_DP<15>
  J2  = GND
  J3  = P5E_CPU1_PE3_TX_C_DP<13>
  J4  = GND
  J5  = P5E_CPU1_PE3_TX_C_DP<11>
  J6  = GND
  J7  = P5E_CPU1_PE3_TX_C_DP<9>
  J8  = GND
  K1  = GND
  K2  = P5E_CPU1_PE2_TX_C_DP<14>
  K3  = GND
  K4  = P5E_CPU1_PE2_TX_C_DP<12>
  K5  = GND
  K6  = P5E_CPU1_PE2_TX_C_DP<10>
  K7  = GND
  K8  = P5E_CPU1_PE2_TX_C_DP<8>
  L1  = P5E_CPU1_PE2_TX_C_DP<15>
  L2  = P5E_CPU1_PE2_TX_C_DN<14>
  L3  = P5E_CPU1_PE2_TX_C_DP<13>
  L4  = P5E_CPU1_PE2_TX_C_DN<12>
  L5  = P5E_CPU1_PE2_TX_C_DP<11>
  L6  = P5E_CPU1_PE2_TX_C_DN<10>
  L7  = P5E_CPU1_PE2_TX_C_DP<9>
  L8  = P5E_CPU1_PE2_TX_C_DN<8>
  M1  = P5E_CPU1_PE2_TX_C_DN<15>
  M2  = GND
  M3  = P5E_CPU1_PE2_TX_C_DN<13>
  M4  = GND
  M5  = P5E_CPU1_PE2_TX_C_DN<11>
  M6  = GND
  M7  = P5E_CPU1_PE2_TX_C_DN<9>
  M8  = GND
  N1  = GND
  N2  = GPU_FPGA_BOOT_EN_BUF
  N3  = GND
  N4  = FM_SMB_1_ALERT_GPU_N
  N5  = GND
  N6  = FM_SMB_2_ALERT_GPU_N
  N7  = GND
  N8  = GPU_FPGA_EROT_RST_BUF_N

(kicad_pcb
	(version 20260206)
	(generator "pcbnew")
	(generator_version "10.0")
	(general
		(thickness 1.6)
		(legacy_teardrops no)
	)
	(paper "A4")
	(title_block
		(title "03242023_DA0F0TMBIJ0_F0T_Motherboard_J_brd_V01_OCP.brd")
		(comment 1 "Grand Teton / footprint 1392 of 6105 (J110), pads 1-31 of 48")
	)
	(layers
		(0 "F.Cu" signal "TOP")
		(4 "In1.Cu" signal "GND")
		(6 "In2.Cu" signal "IN1")
		(8 "In3.Cu" signal "GND1")
		(10 "In4.Cu" signal "IN2")
		(12 "In5.Cu" signal "GND2")
		(14 "In6.Cu" signal "IN3")
		(16 "In7.Cu" signal "GND3")
		(18 "In8.Cu" signal "VCC")
		(20 "In9.Cu" signal "VCC1")
		(22 "In10.Cu" signal "GND4")
		(24 "In11.Cu" signal "IN4")
		(26 "In12.Cu" signal "GND5")
		(28 "In13.Cu" signal "IN5")
		(30 "In14.Cu" signal "GND6")
		(32 "In15.Cu" signal "IN6")
		(34 "In16.Cu" signal "GND7")
		(2 "B.Cu" signal "BOTTOM")
		(9 "F.Adhes" user "F.Adhesive")
		(11 "B.Adhes" user "B.Adhesive")
		(13 "F.Paste" user "Package Geometry/Pastemask Top")
		(15 "B.Paste" user "Package Geometry/Pastemask Bottom")
		(5 "F.SilkS" user "Ref Des/Silkscreen Top")
		(7 "B.SilkS" user "Ref Des/Silkscreen Bottom")
		(1 "F.Mask" user "Board Geometry/Soldermask Top")
		(3 "B.Mask" user "Board Geometry/Soldermask Bottom")
		(17 "Dwgs.User" user "User.Drawings")
		(19 "Cmts.User" user "User.Comments")
		(21 "Eco1.User" user "User.Eco1")
		(23 "Eco2.User" user "User.Eco2")
		(25 "Edge.Cuts" user "Board Geometry/Outline")
		(27 "Margin" user)
		(31 "F.CrtYd" user "Package Geometry/Place Bound Top")
		(29 "B.CrtYd" user "Package Geometry/Place Bound Bottom")
		(35 "F.Fab" user "Ref Des/Assembly Top")
		(33 "B.Fab" user "Ref Des/Assembly Bottom")
	)
	(footprint ""
		(layer "F.Cu")
		(at 125.750066 -440.489848)
		(property "Reference" "J110"
			(at -3.723386 20.59559 0)
			(unlocked yes)
			(layer "F.SilkS")
			(effects
				(font
					(size 0.7874 0.5842)
					(thickness 0.1524)
				)
				(justify left)
			)
		)
		(property "Value" ""
			(at 0 0 0)
			(layer "F.Fab")
			(effects
				(font
					(size 1.27 1.27)
				)
			)
		)
		(duplicate_pad_numbers_are_jumpers no)
		(pad "A1" thru_hole rect
			(at 0 0 180)
			(size 0.766318 0.766318)
			(drill 0.359918)
			(layers "*.Cu" "*.Mask")
			(remove_unused_layers no)
			(net "GPU_FPGA_EROT_RECOV_BUF_N")
			(clearance 0.0508)
			(thermal_gap 0.0508)
			(padstack
				(mode front_inner_back)
				(layer "Inner"
					(shape circle)
					(size 0.766318 0.766318)
					(clearance 0.0508)
				)
				(layer "B.Cu"
					(shape rect)
					(size 0.766318 0.766318)
					(clearance 0.0508)
				)
			)
		)
		(pad "A2" thru_hole circle
			(at 1.999996 0.199898 180)
			(size 0.906272 0.906272)
			(drill 0.499872)
			(layers "*.Cu" "*.Mask")
			(remove_unused_layers no)
			(net "GND")
			(clearance 0.0508)
			(thermal_gap 0.0508)
		)
		(pad "A3" thru_hole circle
			(at 3.999992 0 180)
			(size 0.766318 0.766318)
			(drill 0.359918)
			(layers "*.Cu" "*.Mask")
			(remove_unused_layers no)
			(net "GPU_HMC_PRSNT_N")
			(clearance 0.0508)
			(thermal_gap 0.0508)
		)
		(pad "A4" thru_hole circle
			(at 5.999988 0.199898 180)
			(size 0.906272 0.906272)
			(drill 0.499872)
			(layers "*.Cu" "*.Mask")
			(remove_unused_layers no)
			(net "GND")
			(clearance 0.0508)
			(thermal_gap 0.0508)
		)
		(pad "A5" thru_hole circle
			(at 7.999984 0 180)
			(size 0.766318 0.766318)
			(drill 0.359918)
			(layers "*.Cu" "*.Mask")
			(remove_unused_layers no)
			(net "GPU_BASE_HMC_READY")
			(clearance 0.0508)
			(thermal_gap 0.0508)
		)
		(pad "A6" thru_hole circle
			(at 9.99998 0.199898 180)
			(size 0.906272 0.906272)
			(drill 0.499872)
			(layers "*.Cu" "*.Mask")
			(remove_unused_layers no)
			(net "GND")
			(clearance 0.0508)
			(thermal_gap 0.0508)
		)
		(pad "A7" thru_hole circle
			(at 11.999976 0 180)
			(size 0.766318 0.766318)
			(drill 0.359918)
			(layers "*.Cu" "*.Mask")
			(remove_unused_layers no)
			(net "GPU_BASE_STBY_EN_BUF")
			(clearance 0.0508)
			(thermal_gap 0.0508)
		)
		(pad "A8" thru_hole circle
			(at 13.999972 0.199898 180)
			(size 0.906272 0.906272)
			(drill 0.499872)
			(layers "*.Cu" "*.Mask")
			(remove_unused_layers no)
			(net "GND")
			(clearance 0.0508)
			(thermal_gap 0.0508)
		)
		(pad "B1" thru_hole circle
			(at 0 1.199896 180)
			(size 0.906272 0.906272)
			(drill 0.499872)
			(layers "*.Cu" "*.Mask")
			(remove_unused_layers no)
			(net "GND")
			(clearance 0.0508)
			(thermal_gap 0.0508)
		)
		(pad "B3" thru_hole circle
			(at 3.999992 1.199896 180)
			(size 0.906272 0.906272)
			(drill 0.499872)
			(layers "*.Cu" "*.Mask")
			(remove_unused_layers no)
			(net "GND")
			(clearance 0.0508)
			(thermal_gap 0.0508)
		)
		(pad "B5" thru_hole circle
			(at 7.999984 1.199896 180)
			(size 0.906272 0.906272)
			(drill 0.499872)
			(layers "*.Cu" "*.Mask")
			(remove_unused_layers no)
			(net "GND")
			(clearance 0.0508)
			(thermal_gap 0.0508)
		)
		(pad "B7" thru_hole circle
			(at 11.999976 1.199896 180)
			(size 0.906272 0.906272)
			(drill 0.499872)
			(layers "*.Cu" "*.Mask")
			(remove_unused_layers no)
			(net "GND")
			(clearance 0.0508)
			(thermal_gap 0.0508)
		)
		(pad "D2" thru_hole circle
			(at 1.999996 3.800094 180)
			(size 0.906272 0.906272)
			(drill 0.499872)
			(layers "*.Cu" "*.Mask")
			(remove_unused_layers no)
			(net "GND")
			(clearance 0.0508)
			(thermal_gap 0.0508)
		)
		(pad "D4" thru_hole circle
			(at 5.999988 3.800094 180)
			(size 0.906272 0.906272)
			(drill 0.499872)
			(layers "*.Cu" "*.Mask")
			(remove_unused_layers no)
			(net "GND")
			(clearance 0.0508)
			(thermal_gap 0.0508)
		)
		(pad "D6" thru_hole circle
			(at 9.99998 3.800094 180)
			(size 0.906272 0.906272)
			(drill 0.499872)
			(layers "*.Cu" "*.Mask")
			(remove_unused_layers no)
			(net "GND")
			(clearance 0.0508)
			(thermal_gap 0.0508)
		)
		(pad "D8" thru_hole circle
			(at 13.999972 3.800094 180)
			(size 0.906272 0.906272)
			(drill 0.499872)
			(layers "*.Cu" "*.Mask")
			(remove_unused_layers no)
			(net "GND")
			(clearance 0.0508)
			(thermal_gap 0.0508)
		)
		(pad "E1" thru_hole circle
			(at 0 4.800092 180)
			(size 0.906272 0.906272)
			(drill 0.499872)
			(layers "*.Cu" "*.Mask")
			(remove_unused_layers no)
			(net "GND")
			(clearance 0.0508)
			(thermal_gap 0.0508)
		)
		(pad "E3" thru_hole circle
			(at 3.999992 4.800092 180)
			(size 0.906272 0.906272)
			(drill 0.499872)
			(layers "*.Cu" "*.Mask")
			(remove_unused_layers no)
			(net "GND")
			(clearance 0.0508)
			(thermal_gap 0.0508)
		)
		(pad "E5" thru_hole circle
			(at 7.999984 4.800092 180)
			(size 0.906272 0.906272)
			(drill 0.499872)
			(layers "*.Cu" "*.Mask")
			(remove_unused_layers no)
			(net "GND")
			(clearance 0.0508)
			(thermal_gap 0.0508)
		)
		(pad "E7" thru_hole circle
			(at 11.999976 4.800092 180)
			(size 0.906272 0.906272)
			(drill 0.499872)
			(layers "*.Cu" "*.Mask")
			(remove_unused_layers no)
			(net "GND")
			(clearance 0.0508)
			(thermal_gap 0.0508)
		)
		(pad "G2" thru_hole circle
			(at 1.999996 7.400036 180)
			(size 0.906272 0.906272)
			(drill 0.499872)
			(layers "*.Cu" "*.Mask")
			(remove_unused_layers no)
			(net "GND")
			(clearance 0.0508)
			(thermal_gap 0.0508)
		)
		(pad "G4" thru_hole circle
			(at 5.999988 7.400036 180)
			(size 0.906272 0.906272)
			(drill 0.499872)
			(layers "*.Cu" "*.Mask")
			(remove_unused_layers no)
			(net "GND")
			(clearance 0.0508)
			(thermal_gap 0.0508)
		)
		(pad "G6" thru_hole circle
			(at 9.99998 7.400036 180)
			(size 0.906272 0.906272)
			(drill 0.499872)
			(layers "*.Cu" "*.Mask")
			(remove_unused_layers no)
			(net "GND")
			(clearance 0.0508)
			(thermal_gap 0.0508)
		)
		(pad "G8" thru_hole circle
			(at 13.999972 7.400036 180)
			(size 0.906272 0.906272)
			(drill 0.499872)
			(layers "*.Cu" "*.Mask")
			(remove_unused_layers no)
			(net "GND")
			(clearance 0.0508)
			(thermal_gap 0.0508)
		)
		(pad "H1" thru_hole circle
			(at 0 8.400034 180)
			(size 0.906272 0.906272)
			(drill 0.499872)
			(layers "*.Cu" "*.Mask")
			(remove_unused_layers no)
			(net "GND")
			(clearance 0.0508)
			(thermal_gap 0.0508)
		)
		(pad "H3" thru_hole circle
			(at 3.999992 8.400034 180)
			(size 0.906272 0.906272)
			(drill 0.499872)
			(layers "*.Cu" "*.Mask")
			(remove_unused_layers no)
			(net "GND")
			(clearance 0.0508)
			(thermal_gap 0.0508)
		)
		(pad "H5" thru_hole circle
			(at 7.999984 8.400034 180)
			(size 0.906272 0.906272)
			(drill 0.499872)
			(layers "*.Cu" "*.Mask")
			(remove_unused_layers no)
			(net "GND")
			(clearance 0.0508)
			(thermal_gap 0.0508)
		)
		(pad "H7" thru_hole circle
			(at 11.999976 8.400034 180)
			(size 0.906272 0.906272)
			(drill 0.499872)
			(layers "*.Cu" "*.Mask")
			(remove_unused_layers no)
			(net "GND")
			(clearance 0.0508)
			(thermal_gap 0.0508)
		)
		(pad "J2" thru_hole circle
			(at 1.999996 10.999978 180)
			(size 0.906272 0.906272)
			(drill 0.499872)
			(layers "*.Cu" "*.Mask")
			(remove_unused_layers no)
			(net "GND")
			(clearance 0.0508)
			(thermal_gap 0.0508)
		)
		(pad "J4" thru_hole circle
			(at 5.999988 10.999978 180)
			(size 0.906272 0.906272)
			(drill 0.499872)
			(layers "*.Cu" "*.Mask")
			(remove_unused_layers no)
			(net "GND")
			(clearance 0.0508)
			(thermal_gap 0.0508)
		)
		(pad "J6" thru_hole circle
			(at 9.99998 10.999978 180)
			(size 0.906272 0.906272)
			(drill 0.499872)
			(layers "*.Cu" "*.Mask")
			(remove_unused_layers no)
			(net "GND")
			(clearance 0.0508)
			(thermal_gap 0.0508)
		)
	)
)
